(kicad_pcb
	(version 20260206)
	(generator "pcbnew")
	(generator_version "10.0")
	(general
		(thickness 1.6)
		(legacy_teardrops no)
	)
	(paper "A4")
	(title_block
		(title "03242023_DA0F0TMBIJ0_F0T_Motherboard_J_brd_V01_OCP.brd")
		(comment 1 "Grand Teton / footprints 796-797 of 6105")
	)
	(layers
		(0 "F.Cu" signal "TOP")
		(4 "In1.Cu" signal "GND")
		(6 "In2.Cu" signal "IN1")
		(8 "In3.Cu" signal "GND1")
		(10 "In4.Cu" signal "IN2")
		(12 "In5.Cu" signal "GND2")
		(14 "In6.Cu" signal "IN3")
		(16 "In7.Cu" signal "GND3")
		(18 "In8.Cu" signal "VCC")
		(20 "In9.Cu" signal "VCC1")
		(22 "In10.Cu" signal "GND4")
		(24 "In11.Cu" signal "IN4")
		(26 "In12.Cu" signal "GND5")
		(28 "In13.Cu" signal "IN5")
		(30 "In14.Cu" signal "GND6")
		(32 "In15.Cu" signal "IN6")
		(34 "In16.Cu" signal "GND7")
		(2 "B.Cu" signal "BOTTOM")
		(9 "F.Adhes" user "F.Adhesive")
		(11 "B.Adhes" user "B.Adhesive")
		(13 "F.Paste" user "Package Geometry/Pastemask Top")
		(15 "B.Paste" user "Package Geometry/Pastemask Bottom")
		(5 "F.SilkS" user "Ref Des/Silkscreen Top")
		(7 "B.SilkS" user "Ref Des/Silkscreen Bottom")
		(1 "F.Mask" user "Board Geometry/Soldermask Top")
		(3 "B.Mask" user "Board Geometry/Soldermask Bottom")
		(17 "Dwgs.User" user "User.Drawings")
		(19 "Cmts.User" user "User.Comments")
		(21 "Eco1.User" user "User.Eco1")
		(23 "Eco2.User" user "User.Eco2")
		(25 "Edge.Cuts" user "Board Geometry/Outline")
		(27 "Margin" user)
		(31 "F.CrtYd" user "Package Geometry/Place Bound Top")
		(29 "B.CrtYd" user "Package Geometry/Place Bound Bottom")
		(35 "F.Fab" user "Ref Des/Assembly Top")
		(33 "B.Fab" user "Ref Des/Assembly Bottom")
	)
	(footprint ""
		(layer "F.Cu")
		(at 32.06115 -129.633472 90)
		(property "Reference" "PU22"
			(at -6.968236 -4.331208 0)
			(unlocked yes)
			(layer "F.SilkS")
			(effects
				(font
					(size 0.7874 0.5842)
					(thickness 0.1524)
				)
			)
		)
		(property "Value" ""
			(at 0 0 90)
			(layer "F.Fab")
			(effects
				(font
					(size 1.27 1.27)
				)
			)
		)
		(duplicate_pad_numbers_are_jumpers no)
		(fp_line
			(start 0.1778 -3.2385)
			(end 0.1778 -2.8575)
			(stroke
				(width 0.1524)
				(type default)
			)
			(layer "F.SilkS")
		)
		(fp_line
			(start -1.8034 -2.8702)
			(end -1.8034 -3.6322)
			(stroke
				(width 0.1524)
				(type default)
			)
			(layer "F.SilkS")
		)
		(fp_line
			(start 2.500122 -2.500122)
			(end 2.500122 -2.015998)
			(stroke
				(width 0.1524)
				(type default)
			)
			(layer "F.SilkS")
		)
		(fp_line
			(start 2.015998 -2.500122)
			(end 2.500122 -2.500122)
			(stroke
				(width 0.1524)
				(type default)
			)
			(layer "F.SilkS")
		)
		(fp_line
			(start -2.500122 -2.500122)
			(end -2.015998 -2.500122)
			(stroke
				(width 0.1524)
				(type default)
			)
			(layer "F.SilkS")
		)
		(fp_line
			(start -2.500122 -2.015998)
			(end -2.500122 -2.500122)
			(stroke
				(width 0.1524)
				(type default)
			)
			(layer "F.SilkS")
		)
		(fp_line
			(start 2.8702 -1.778)
			(end 3.6322 -1.778)
			(stroke
				(width 0.1524)
				(type default)
			)
			(layer "F.SilkS")
		)
		(fp_line
			(start -3.2639 -0.1778)
			(end -2.8829 -0.1778)
			(stroke
				(width 0.1524)
				(type default)
			)
			(layer "F.SilkS")
		)
		(fp_line
			(start 2.8829 0.2032)
			(end 3.2639 0.2032)
			(stroke
				(width 0.1524)
				(type default)
			)
			(layer "F.SilkS")
		)
		(fp_line
			(start -3.6576 1.8034)
			(end -2.8956 1.8034)
			(stroke
				(width 0.1524)
				(type default)
			)
			(layer "F.SilkS")
		)
		(fp_line
			(start 2.500122 2.015998)
			(end 2.500122 2.500122)
			(stroke
				(width 0.1524)
				(type default)
			)
			(layer "F.SilkS")
		)
		(fp_line
			(start 2.500122 2.500122)
			(end 2.015998 2.500122)
			(stroke
				(width 0.1524)
				(type default)
			)
			(layer "F.SilkS")
		)
		(fp_line
			(start -2.015998 2.500122)
			(end -2.500122 2.500122)
			(stroke
				(width 0.1524)
				(type default)
			)
			(layer "F.SilkS")
		)
		(fp_line
			(start -2.500122 2.500122)
			(end -2.500122 2.018538)
			(stroke
				(width 0.1524)
				(type default)
			)
			(layer "F.SilkS")
		)
		(fp_line
			(start -0.2032 2.8829)
			(end -0.2032 3.2639)
			(stroke
				(width 0.1524)
				(type default)
			)
			(layer "F.SilkS")
		)
		(fp_line
			(start 1.778 3.6322)
			(end 1.778 2.8702)
			(stroke
				(width 0.1524)
				(type default)
			)
			(layer "F.SilkS")
		)
		(fp_poly
			(pts
				(xy -3.504184 -1.508506) (xy -3.504184 -2.09169) (xy -2.921 -1.800098)
			)
			(stroke
				(width 0)
				(type default)
			)
			(fill yes)
			(layer "F.SilkS")
		)
		(fp_line
			(start 0.1778 -3.2385)
			(end 0.1778 -2.8575)
			(stroke
				(width 0.1)
				(type default)
			)
			(layer "F.Fab")
		)
		(fp_line
			(start -1.8034 -2.8702)
			(end -1.8034 -3.6322)
			(stroke
				(width 0.1)
				(type default)
			)
			(layer "F.Fab")
		)
		(fp_line
			(start 2.500122 -2.500122)
			(end 2.500122 2.500122)
			(stroke
				(width 0.1)
				(type default)
			)
			(layer "F.Fab")
		)
		(fp_line
			(start -2.500122 -2.500122)
			(end 2.500122 -2.500122)
			(stroke
				(width 0.1)
				(type default)
			)
			(layer "F.Fab")
		)
		(fp_line
			(start 2.8702 -1.778)
			(end 3.6322 -1.778)
			(stroke
				(width 0.1)
				(type default)
			)
			(layer "F.Fab")
		)
		(fp_line
			(start -3.2639 -0.1778)
			(end -2.8829 -0.1778)
			(stroke
				(width 0.1)
				(type default)
			)
			(layer "F.Fab")
		)
		(fp_line
			(start 2.8829 0.2032)
			(end 3.2639 0.2032)
			(stroke
				(width 0.1)
				(type default)
			)
			(layer "F.Fab")
		)
		(fp_line
			(start -3.6576 1.8034)
			(end -2.8956 1.8034)
			(stroke
				(width 0.1)
				(type default)
			)
			(layer "F.Fab")
		)
		(fp_line
			(start 2.500122 2.500122)
			(end -2.500122 2.500122)
			(stroke
				(width 0.1)
				(type default)
			)
			(layer "F.Fab")
		)
		(fp_line
			(start -2.500122 2.500122)
			(end -2.500122 -2.500122)
			(stroke
				(width 0.1)
				(type default)
			)
			(layer "F.Fab")
		)
		(fp_line
			(start -0.2032 2.8829)
			(end -0.2032 3.2639)
			(stroke
				(width 0.1)
				(type default)
			)
			(layer "F.Fab")
		)
		(fp_line
			(start 1.778 3.6322)
			(end 1.778 2.8702)
			(stroke
				(width 0.1)
				(type default)
			)
			(layer "F.Fab")
		)
		(fp_poly
			(pts
				(xy -2.921 -1.800098) (xy -3.504184 -1.508506) (xy -3.504184 -2.09169)
			)
			(stroke
				(width 0)
				(type default)
			)
			(fill yes)
			(layer "F.Fab")
		)
		(fp_text user "31"
			(at 2.371598 -4.09321 0)
			(unlocked yes)
			(layer "F.SilkS")
			(effects
				(font
					(size 0.635 0.4064)
					(thickness 0.1524)
				)
				(justify left)
			)
		)
		(fp_text user "40"
			(at -2.624074 -3.77825 0)
			(unlocked yes)
			(layer "F.SilkS")
			(effects
				(font
					(size 0.635 0.4064)
					(thickness 0.1524)
				)
				(justify left)
			)
		)
		(fp_text user "30"
			(at 3.873246 -1.40335 0)
			(unlocked yes)
			(layer "F.SilkS")
			(effects
				(font
					(size 0.635 0.4064)
					(thickness 0.1524)
				)
				(justify left)
			)
		)
		(fp_text user "21"
			(at 4.815586 -0.18669 0)
			(unlocked yes)
			(layer "F.SilkS")
			(effects
				(font
					(size 0.635 0.4064)
					(thickness 0.1524)
				)
				(justify left)
			)
		)
		(fp_text user "10"
			(at -3.165094 2.18821 0)
			(unlocked yes)
			(layer "F.SilkS")
			(effects
				(font
					(size 0.635 0.4064)
					(thickness 0.1524)
				)
				(justify left)
			)
		)
		(fp_text user "11"
			(at -2.166874 2.85877 0)
			(unlocked yes)
			(layer "F.SilkS")
			(effects
				(font
					(size 0.635 0.4064)
					(thickness 0.1524)
				)
				(justify left)
			)
		)
		(fp_text user "20"
			(at 2.277618 2.92735 0)
			(unlocked yes)
			(layer "F.SilkS")
			(effects
				(font
					(size 0.635 0.4064)
					(thickness 0.1524)
				)
				(justify left)
			)
		)
		(fp_text user "31"
			(at 1.8542 -3.172968 90)
			(unlocked yes)
			(layer "F.Fab")
			(effects
				(font
					(size 0.635 0.4064)
					(thickness 0.1524)
				)
				(justify left)
			)
		)
		(fp_text user "40"
			(at -3.2004 -3.096768 90)
			(unlocked yes)
			(layer "F.Fab")
			(effects
				(font
					(size 0.635 0.4064)
					(thickness 0.1524)
				)
				(justify left)
			)
		)
		(fp_text user "30"
			(at 3.096768 -2.51714 0)
			(unlocked yes)
			(layer "F.Fab")
			(effects
				(font
					(size 0.635 0.4064)
					(thickness 0.1524)
				)
				(justify left)
			)
		)
		(fp_text user "21"
			(at 2.974848 1.82372 0)
			(unlocked yes)
			(layer "F.Fab")
			(effects
				(font
					(size 0.635 0.4064)
					(thickness 0.1524)
				)
				(justify left)
			)
		)
		(fp_text user "10"
			(at -3.253232 2.1336 0)
			(unlocked yes)
			(layer "F.Fab")
			(effects
				(font
					(size 0.635 0.4064)
					(thickness 0.1524)
				)
				(justify left)
			)
		)
		(fp_text user "20"
			(at 2.0828 3.253232 90)
			(unlocked yes)
			(layer "F.Fab")
			(effects
				(font
					(size 0.635 0.4064)
					(thickness 0.1524)
				)
				(justify left)
			)
		)
		(fp_text user "11"
			(at -2.8702 3.278632 90)
			(unlocked yes)
			(layer "F.Fab")
			(effects
				(font
					(size 0.635 0.4064)
					(thickness 0.1524)
				)
				(justify left)
			)
		)
		(pad "1" smd rect
			(at -2.400046 -1.800098)
			(size 0.1778 0.6096)
			(layers "F.Cu" "F.Mask" "F.Paste")
			(net "PVCCFA_EHV_CPU1_BPWM1")
		)
		(pad "2" smd rect
			(at -2.400046 -1.400048)
			(size 0.1778 0.6096)
			(layers "F.Cu" "F.Mask" "F.Paste")
			(net "NC_PVCCINFAON_CPU1_APWM7")
		)
		(pad "3" smd rect
			(at -2.400046 -0.999998)
			(size 0.1778 0.6096)
			(layers "F.Cu" "F.Mask" "F.Paste")
			(net "NC_PVCCINFAON_CPU1_APWM6")
		)
		(pad "4" smd rect
			(at -2.400046 -0.599948)
			(size 0.1778 0.6096)
			(layers "F.Cu" "F.Mask" "F.Paste")
			(net "NC_PVCCINFAON_CPU1_APWM5")
		)
		(pad "5" smd rect
			(at -2.400046 -0.199898)
			(size 0.1778 0.6096)
			(layers "F.Cu" "F.Mask" "F.Paste")
			(net "NC_PVCCINFAON_CPU1_APWM4")
		)
		(pad "6" smd rect
			(at -2.400046 0.199898)
			(size 0.1778 0.6096)
			(layers "F.Cu" "F.Mask" "F.Paste")
			(net "NC_PVCCINFAON_CPU1_APWM3")
		)
		(pad "7" smd rect
			(at -2.400046 0.599948)
			(size 0.1778 0.6096)
			(layers "F.Cu" "F.Mask" "F.Paste")
			(net "PVCCINFAON_CPU1_APWM2")
		)
		(pad "8" smd rect
			(at -2.400046 0.999998)
			(size 0.1778 0.6096)
			(layers "F.Cu" "F.Mask" "F.Paste")
			(net "PVCCINFAON_CPU1_APWM1")
		)
		(pad "9" smd rect
			(at -2.400046 1.400048)
			(size 0.1778 0.6096)
			(layers "F.Cu" "F.Mask" "F.Paste")
			(net "SMB_DIO_PVCCINFAON_CPU1")
		)
		(pad "10" smd rect
			(at -2.400046 1.800098)
			(size 0.1778 0.6096)
			(layers "F.Cu" "F.Mask" "F.Paste")
			(net "SMB_CLK_PVCCINFAON_CPU1")
		)
		(pad "11" smd rect
			(at -1.800098 2.400046 90)
			(size 0.1778 0.6096)
			(layers "F.Cu" "F.Mask" "F.Paste")
			(net "NC_PVCCINFAON_CPU1_SMB_ALERT")
		)
		(pad "12" smd rect
			(at -1.400048 2.400046 90)
			(size 0.1778 0.6096)
			(layers "F.Cu" "F.Mask" "F.Paste")
			(net "PWRGD_PVCCINFAON_CPU1_R")
		)
		(pad "13" smd rect
			(at -0.999998 2.400046 90)
			(size 0.1778 0.6096)
			(layers "F.Cu" "F.Mask" "F.Paste")
			(net "PVCCINFAON_CPU1_EN_R")
		)
		(pad "14" smd rect
			(at -0.599948 2.400046 90)
			(size 0.1778 0.6096)
			(layers "F.Cu" "F.Mask" "F.Paste")
			(net "IRQ_PVCCFA_CPU1_VRHOT_N")
		)
		(pad "15" smd rect
			(at -0.199898 2.400046 90)
			(size 0.1778 0.6096)
			(layers "F.Cu" "F.Mask" "F.Paste")
			(net "PVCCINFAON_CPU1_PIN_ALERT")
		)
		(pad "16" smd rect
			(at 0.199898 2.400046 90)
			(size 0.1778 0.6096)
			(layers "F.Cu" "F.Mask" "F.Paste")
			(net "PWRGD_PVCCFA_EHV_CPU1_R")
		)
		(pad "17" smd rect
			(at 0.599948 2.400046 90)
			(size 0.1778 0.6096)
			(layers "F.Cu" "F.Mask" "F.Paste")
			(net "SVID_CLK_PVCCINFAON_CPU1_R")
		)
		(pad "18" smd rect
			(at 0.999998 2.400046 90)
			(size 0.1778 0.6096)
			(layers "F.Cu" "F.Mask" "F.Paste")
			(net "SVID_DIO_PVCCINFAON_CPU1_R")
		)
		(pad "19" smd rect
			(at 1.400048 2.400046 90)
			(size 0.1778 0.6096)
			(layers "F.Cu" "F.Mask" "F.Paste")
			(net "SVID_ALERT_PVCCINFAON_CPU1_R")
		)
		(pad "20" smd rect
			(at 1.800098 2.400046 90)
			(size 0.1778 0.6096)
			(layers "F.Cu" "F.Mask" "F.Paste")
			(net "PVCCFA_EHV_CPU1_EN_R")
		)
		(pad "21" smd rect
			(at 2.400046 1.800098)
			(size 0.1778 0.6096)
			(layers "F.Cu" "F.Mask" "F.Paste")
			(net "SH_PVCCINFAON_CPU1_R")
		)
		(pad "22" smd rect
			(at 2.400046 1.400048)
			(size 0.1778 0.6096)
			(layers "F.Cu" "F.Mask" "F.Paste")
			(net "VSENSE_PVCCINFAON_CPU1_DN")
		)
		(pad "23" smd rect
			(at 2.400046 0.999998)
			(size 0.1778 0.6096)
			(layers "F.Cu" "F.Mask" "F.Paste")
			(net "PVCCINFAON_CPU1_ACSP1")
		)
		(pad "24" smd rect
			(at 2.400046 0.599948)
			(size 0.1778 0.6096)
			(layers "F.Cu" "F.Mask" "F.Paste")
			(net "PVCCINFAON_CPU1_ACSP2")
		)
		(pad "25" smd rect
			(at 2.400046 0.199898)
			(size 0.1778 0.6096)
			(layers "F.Cu" "F.Mask" "F.Paste")
			(net "NC_PVCCINFAON_CPU1_ACSP3")
		)
		(pad "26" smd rect
			(at 2.400046 -0.199898)
			(size 0.1778 0.6096)
			(layers "F.Cu" "F.Mask" "F.Paste")
			(net "NC_PVCCINFAON_CPU1_ACSP4")
		)
		(pad "27" smd rect
			(at 2.400046 -0.599948)
			(size 0.1778 0.6096)
			(layers "F.Cu" "F.Mask" "F.Paste")
			(net "NC_PVCCINFAON_CPU1_ACSP5")
		)
		(pad "28" smd rect
			(at 2.400046 -0.999998)
			(size 0.1778 0.6096)
			(layers "F.Cu" "F.Mask" "F.Paste")
			(net "NC_PVCCINFAON_CPU1_ACSP6")
		)
		(pad "29" smd rect
			(at 2.400046 -1.400048)
			(size 0.1778 0.6096)
			(layers "F.Cu" "F.Mask" "F.Paste")
			(net "NC_PVCCINFAON_CPU1_ACSP7")
		)
		(pad "30" smd rect
			(at 2.400046 -1.800098)
			(size 0.1778 0.6096)
			(layers "F.Cu" "F.Mask" "F.Paste")
			(net "PVCCFA_EHV_CPU1_BCSP1")
		)
		(pad "31" smd rect
			(at 1.800098 -2.400046 90)
			(size 0.1778 0.6096)
			(layers "F.Cu" "F.Mask" "F.Paste")
			(net "VSENSE_PVCCFA_EHV_CPU1_DN")
		)
		(pad "32" smd rect
			(at 1.400048 -2.400046 90)
			(size 0.1778 0.6096)
			(layers "F.Cu" "F.Mask" "F.Paste")
			(net "SH_PVCCFA_EHV_CPU1_R")
		)
		(pad "33" smd rect
			(at 0.999998 -2.400046 90)
			(size 0.1778 0.6096)
			(layers "F.Cu" "F.Mask" "F.Paste")
			(net "PVCCINFAON_CPU1_VR_FAULT")
		)
		(pad "34" smd rect
			(at 0.599948 -2.400046 90)
			(size 0.1778 0.6096)
			(layers "F.Cu" "F.Mask" "F.Paste")
			(net "PVCCINFAON_CPU1_ADDR")
		)
		(pad "35" smd rect
			(at 0.199898 -2.400046 90)
			(size 0.1778 0.6096)
			(layers "F.Cu" "F.Mask" "F.Paste")
			(net "PVCCINFAON_CPU1_ATSEN")
		)
		(pad "36" smd rect
			(at -0.199898 -2.400046 90)
			(size 0.1778 0.6096)
			(layers "F.Cu" "F.Mask" "F.Paste")
			(net "PVCCFA_EHV_CPU1_BTSEN")
		)
		(pad "37" smd rect
			(at -0.599948 -2.400046 90)
			(size 0.1778 0.6096)
			(layers "F.Cu" "F.Mask" "F.Paste")
			(net "PVCCINFAON_CPU1_CSPIN")
		)
		(pad "38" smd rect
			(at -0.999998 -2.400046 90)
			(size 0.1778 0.6096)
			(layers "F.Cu" "F.Mask" "F.Paste")
			(net "PVCCINFAON_CPU1_VIN_CSNIN")
		)
		(pad "39" smd rect
			(at -1.400048 -2.400046 90)
			(size 0.1778 0.6096)
			(layers "F.Cu" "F.Mask" "F.Paste")
			(net "PVCCINFAON_CPU1_VCC")
		)
		(pad "40" smd rect
			(at -1.800098 -2.400046 90)
			(size 0.1778 0.6096)
			(layers "F.Cu" "F.Mask" "F.Paste")
			(net "PVCCINFAON_CPU1_VREF")
		)
		(pad "TH" smd rect
			(at 0 0 90)
			(size 3.6576 3.6576)
			(layers "F.Cu" "F.Mask" "F.Paste")
			(net "GND")
		)
		(zone
			(layer "F.Cu")
			(hatch none 0.5)
			(connect_pads
				(clearance 0)
			)
			(min_thickness 0.25)
			(keepout
				(tracks not_allowed)
				(vias allowed)
				(pads allowed)
				(copperpour not_allowed)
				(footprints allowed)
			)
			(placement
				(enabled no)
				(sheetname "")
			)
			(fill
				(thermal_gap 0.5)
				(thermal_bridge_width 0.5)
				(island_removal_mode 0)
			)
			(polygon
				(pts
					(xy 30.02915 -127.601472) (xy 30.02915 -131.665472) (xy 34.09315 -131.665472) (xy 34.09315 -127.601472)
					(xy 30.20695 -127.601472) (xy 30.20695 -127.753872) (xy 33.94075 -127.753872) (xy 33.94075 -131.513072)
					(xy 30.18155 -131.513072) (xy 30.18155 -127.601472)
				)
			)
		)
	)
	(footprint ""
		(layer "F.Cu")
		(at 239.152684 -54.736238 180)
		(property "Reference" "C1994"
			(at 0 0 180)
			(layer "F.SilkS")
			(hide yes)
			(effects
				(font
					(size 1.27 1.27)
				)
			)
		)
		(property "Value" ""
			(at 0 0 180)
			(layer "F.Fab")
			(effects
				(font
					(size 1.27 1.27)
				)
			)
		)
		(duplicate_pad_numbers_are_jumpers no)
		(fp_line
			(start 0.299974 0.150114)
			(end -0.299974 0.150114)
			(stroke
				(width 0.1)
				(type default)
			)
			(layer "F.Fab")
		)
		(fp_line
			(start 0.299974 -0.150114)
			(end 0.299974 0.150114)
			(stroke
				(width 0.1)
				(type default)
			)
			(layer "F.Fab")
		)
		(fp_line
			(start -0.299974 0.150114)
			(end -0.299974 -0.150114)
			(stroke
				(width 0.1)
				(type default)
			)
			(layer "F.Fab")
		)
		(fp_line
			(start -0.299974 -0.150114)
			(end 0.299974 -0.150114)
			(stroke
				(width 0.1)
				(type default)
			)
			(layer "F.Fab")
		)
		(pad "1" smd rect
			(at -0.2667 0 180)
			(size 0.3048 0.381)
			(layers "F.Cu" "F.Mask" "F.Paste")
			(net "P3E_PCH_E1S_TX_DN<1>")
		)
		(pad "2" smd rect
			(at 0.2667 0 180)
			(size 0.3048 0.381)
			(layers "F.Cu" "F.Mask" "F.Paste")
			(net "P3E_PCH_E1S_TX_C_DN<1>")
		)
		(zone
			(layer "In1.Cu")
			(hatch none 0.5)
			(connect_pads
				(clearance 0)
			)
			(min_thickness 0.25)
			(keepout
				(tracks not_allowed)
				(vias allowed)
				(pads allowed)
				(copperpour not_allowed)
				(footprints allowed)
			)
			(placement
				(enabled no)
				(sheetname "")
			)
			(fill
				(thermal_gap 0.5)
				(thermal_bridge_width 0.5)
				(island_removal_mode 0)
			)
			(polygon
				(pts
					(arc
						(start 239.012984 -54.976522)
						(mid 239.066866 -54.954204)
						(end 239.089184 -54.900322)
					)
					(arc
						(start 239.089184 -54.570122)
						(mid 239.066866 -54.51624)
						(end 239.012984 -54.493922)
					)
					(arc
						(start 238.758984 -54.493922)
						(mid 238.705102 -54.51624)
						(end 238.682784 -54.570122)
					)
					(arc
						(start 238.682784 -54.900322)
						(mid 238.705102 -54.954204)
						(end 238.758984 -54.976522)
					)
				)
			)
		)
		(zone
			(layer "In1.Cu")
			(hatch none 0.5)
			(connect_pads
				(clearance 0)
			)
			(min_thickness 0.25)
			(keepout
				(tracks not_allowed)
				(vias allowed)
				(pads allowed)
				(copperpour not_allowed)
				(footprints allowed)
			)
			(placement
				(enabled no)
				(sheetname "")
			)
			(fill
				(thermal_gap 0.5)
				(thermal_bridge_width 0.5)
				(island_removal_mode 0)
			)
			(polygon
				(pts
					(arc
						(start 239.546384 -54.976522)
						(mid 239.600266 -54.954204)
						(end 239.622584 -54.900322)
					)
					(arc
						(start 239.622584 -54.570122)
						(mid 239.600266 -54.51624)
						(end 239.546384 -54.493922)
					)
					(arc
						(start 239.292384 -54.493922)
						(mid 239.238502 -54.51624)
						(end 239.216184 -54.570122)
					)
					(arc
						(start 239.216184 -54.900322)
						(mid 239.238502 -54.954204)
						(end 239.292384 -54.976522)
					)
				)
			)
		)
	)
)
